(kicad_pcb
	(version 20260206)
	(generator "pcbnew")
	(generator_version "10.0")
	(general
		(thickness 1.6)
		(legacy_teardrops no)
	)
	(paper "A4")
	(title_block
		(title "Bryce Canyon_R.DPB_16317-1_OCP.brd")
		(comment 1 "Bryce Canyon / footprints 887-893 of 2099")
	)
	(layers
		(0 "F.Cu" signal "TOP")
		(4 "In1.Cu" signal "L2GND")
		(6 "In2.Cu" signal "L3")
		(8 "In3.Cu" signal "L4VCC")
		(10 "In4.Cu" signal "L5VCC")
		(12 "In5.Cu" signal "L6")
		(14 "In6.Cu" signal "L7GND")
		(2 "B.Cu" signal "BOTTOM")
		(9 "F.Adhes" user "F.Adhesive")
		(11 "B.Adhes" user "B.Adhesive")
		(13 "F.Paste" user "Package Geometry/Pastemask Top")
		(15 "B.Paste" user "Package Geometry/Pastemask Bottom")
		(5 "F.SilkS" user "Ref Des/Silkscreen Top")
		(7 "B.SilkS" user "Ref Des/Silkscreen Bottom")
		(1 "F.Mask" user "Board Geometry/Soldermask Top")
		(3 "B.Mask" user "Board Geometry/Soldermask Bottom")
		(17 "Dwgs.User" user "User.Drawings")
		(19 "Cmts.User" user "User.Comments")
		(21 "Eco1.User" user "User.Eco1")
		(23 "Eco2.User" user "User.Eco2")
		(25 "Edge.Cuts" user "Board Geometry/Outline")
		(27 "Margin" user)
		(31 "F.CrtYd" user "Package Geometry/Place Bound Top")
		(29 "B.CrtYd" user "Package Geometry/Place Bound Bottom")
		(35 "F.Fab" user "Ref Des/Assembly Top")
		(33 "B.Fab" user "Ref Des/Assembly Bottom")
	)
	(footprint ""
		(layer "F.Cu")
		(at 282.829 -345.059 -90)
		(property "Reference" "R493"
			(at 0 0 270)
			(layer "F.SilkS")
			(hide yes)
			(effects
				(font
					(size 1.27 1.27)
				)
			)
		)
		(property "Value" "10KR2F-2-GP"
			(at 0.064008 -3.993896 270)
			(unlocked yes)
			(layer "F.Fab")
			(hide yes)
			(effects
				(font
					(size 1.016 1.016)
					(thickness 0.1524)
				)
			)
		)
		(property "Device Type" "R402H16"
			(at 0.064008 -5.517896 270)
			(unlocked yes)
			(layer "F.Fab")
			(hide yes)
			(effects
				(font
					(size 1.016 1.016)
					(thickness 0.1524)
				)
			)
		)
		(duplicate_pad_numbers_are_jumpers no)
		(fp_line
			(start -0.508 -0.9398)
			(end -0.508 0.9398)
			(stroke
				(width 0.1524)
				(type default)
			)
			(layer "F.SilkS")
		)
		(fp_line
			(start 0.508 -0.9398)
			(end -0.508 -0.9398)
			(stroke
				(width 0.1524)
				(type default)
			)
			(layer "F.SilkS")
		)
		(fp_rect
			(start -0.508 0.9398)
			(end 0.508 -0.9398)
			(stroke
				(width 0)
				(type default)
			)
			(fill no)
			(layer "F.CrtYd")
		)
		(fp_rect
			(start -0.508 0.9398)
			(end 0.508 -0.9398)
			(stroke
				(width 0)
				(type default)
			)
			(fill no)
			(layer "F.Fab")
		)
		(pad "1" smd custom
			(at 0 -0.4445 270)
			(size 0.1397 0.1397)
			(layers "F.Cu" "F.Mask" "F.Paste")
			(net "P12V_IN")
			(options
				(clearance outline)
				(anchor circle)
			)
			(primitives
				(gr_poly
					(pts
						(arc
							(start -0.1778 -0.2794)
							(mid -0.249642 -0.249642)
							(end -0.2794 -0.1778)
						)
						(arc
							(start -0.2794 0.1778)
							(mid -0.249642 0.249642)
							(end -0.1778 0.2794)
						)
						(arc
							(start 0.1778 0.2794)
							(mid 0.249642 0.249642)
							(end 0.2794 0.1778)
						)
						(arc
							(start 0.2794 -0.1778)
							(mid 0.249642 -0.249642)
							(end 0.1778 -0.2794)
						)
					)
					(width 0)
					(fill yes)
				)
			)
		)
		(pad "2" smd custom
			(at 0 0.4445 270)
			(size 0.1397 0.1397)
			(layers "F.Cu" "F.Mask" "F.Paste")
			(net "P3V3_IN_EN")
			(options
				(clearance outline)
				(anchor circle)
			)
			(primitives
				(gr_poly
					(pts
						(arc
							(start -0.1778 -0.2794)
							(mid -0.249642 -0.249642)
							(end -0.2794 -0.1778)
						)
						(arc
							(start -0.2794 0.1778)
							(mid -0.249642 0.249642)
							(end -0.1778 0.2794)
						)
						(arc
							(start 0.1778 0.2794)
							(mid 0.249642 0.249642)
							(end 0.2794 0.1778)
						)
						(arc
							(start 0.2794 -0.1778)
							(mid 0.249642 -0.249642)
							(end 0.1778 -0.2794)
						)
					)
					(width 0)
					(fill yes)
				)
			)
		)
	)
	(footprint ""
		(layer "F.Cu")
		(at 32.149796 -375.6914 -90)
		(property "Reference" "R1305"
			(at 0 0 270)
			(layer "F.SilkS")
			(hide yes)
			(effects
				(font
					(size 1.27 1.27)
				)
			)
		)
		(property "Value" "4K7R2F-GP"
			(at 0.064008 -3.993896 270)
			(unlocked yes)
			(layer "F.Fab")
			(hide yes)
			(effects
				(font
					(size 1.016 1.016)
					(thickness 0.1524)
				)
			)
		)
		(property "Device Type" "R402H16"
			(at 0.064008 -5.517896 270)
			(unlocked yes)
			(layer "F.Fab")
			(hide yes)
			(effects
				(font
					(size 1.016 1.016)
					(thickness 0.1524)
				)
			)
		)
		(duplicate_pad_numbers_are_jumpers no)
		(fp_line
			(start -0.508 -0.9398)
			(end -0.508 0.9398)
			(stroke
				(width 0.1524)
				(type default)
			)
			(layer "F.SilkS")
		)
		(fp_line
			(start 0.508 -0.9398)
			(end -0.508 -0.9398)
			(stroke
				(width 0.1524)
				(type default)
			)
			(layer "F.SilkS")
		)
		(fp_rect
			(start -0.508 0.9398)
			(end 0.508 -0.9398)
			(stroke
				(width 0)
				(type default)
			)
			(fill no)
			(layer "F.CrtYd")
		)
		(fp_rect
			(start -0.508 0.9398)
			(end 0.508 -0.9398)
			(stroke
				(width 0)
				(type default)
			)
			(fill no)
			(layer "F.Fab")
		)
		(pad "1" smd custom
			(at 0 -0.4445 270)
			(size 0.1397 0.1397)
			(layers "F.Cu" "F.Mask" "F.Paste")
			(net "FAN_YELLOW_LED0")
			(options
				(clearance outline)
				(anchor circle)
			)
			(primitives
				(gr_poly
					(pts
						(arc
							(start -0.1778 -0.2794)
							(mid -0.249642 -0.249642)
							(end -0.2794 -0.1778)
						)
						(arc
							(start -0.2794 0.1778)
							(mid -0.249642 0.249642)
							(end -0.1778 0.2794)
						)
						(arc
							(start 0.1778 0.2794)
							(mid 0.249642 0.249642)
							(end 0.2794 0.1778)
						)
						(arc
							(start 0.2794 -0.1778)
							(mid 0.249642 -0.249642)
							(end 0.1778 -0.2794)
						)
					)
					(width 0)
					(fill yes)
				)
			)
		)
		(pad "2" smd custom
			(at 0 0.4445 270)
			(size 0.1397 0.1397)
			(layers "F.Cu" "F.Mask" "F.Paste")
			(net "FAN_LED0_D2")
			(options
				(clearance outline)
				(anchor circle)
			)
			(primitives
				(gr_poly
					(pts
						(arc
							(start -0.1778 -0.2794)
							(mid -0.249642 -0.249642)
							(end -0.2794 -0.1778)
						)
						(arc
							(start -0.2794 0.1778)
							(mid -0.249642 0.249642)
							(end -0.1778 0.2794)
						)
						(arc
							(start 0.1778 0.2794)
							(mid 0.249642 0.249642)
							(end 0.2794 0.1778)
						)
						(arc
							(start 0.2794 -0.1778)
							(mid 0.249642 -0.249642)
							(end 0.1778 -0.2794)
						)
					)
					(width 0)
					(fill yes)
				)
			)
		)
	)
	(footprint ""
		(layer "F.Cu")
		(at 265.625072 -344.370406 90)
		(property "Reference" "R1053"
			(at 0 0 90)
			(layer "F.SilkS")
			(hide yes)
			(effects
				(font
					(size 1.27 1.27)
				)
			)
		)
		(property "Value" "10R5F-1-GP"
			(at 0 -8.9535 90)
			(unlocked yes)
			(layer "F.Fab")
			(hide yes)
			(effects
				(font
					(size 1.27 1.016)
					(thickness 0.1524)
				)
			)
		)
		(property "Device Type" "R805H24"
			(at 0 -10.6299 90)
			(unlocked yes)
			(layer "F.Fab")
			(hide yes)
			(effects
				(font
					(size 1.27 1.016)
					(thickness 0.1524)
				)
			)
		)
		(duplicate_pad_numbers_are_jumpers no)
		(fp_line
			(start 0.889 -1.7018)
			(end -0.889 -1.7018)
			(stroke
				(width 0.1524)
				(type default)
			)
			(layer "F.SilkS")
		)
		(fp_line
			(start 0.889 -1.7018)
			(end 0.889 -0.381)
			(stroke
				(width 0.1524)
				(type default)
			)
			(layer "F.SilkS")
		)
		(fp_line
			(start -0.889 -1.7018)
			(end -0.889 0.2794)
			(stroke
				(width 0.1524)
				(type default)
			)
			(layer "F.SilkS")
		)
		(fp_line
			(start -0.889 0.0762)
			(end -0.889 1.7018)
			(stroke
				(width 0.1524)
				(type default)
			)
			(layer "F.SilkS")
		)
		(fp_line
			(start 0.889 1.7018)
			(end 0.889 -0.508)
			(stroke
				(width 0.1524)
				(type default)
			)
			(layer "F.SilkS")
		)
		(fp_line
			(start -0.889 1.7018)
			(end 0.889 1.7018)
			(stroke
				(width 0.1524)
				(type default)
			)
			(layer "F.SilkS")
		)
		(fp_poly
			(pts
				(xy 0.9652 -1.778) (xy 0.9652 1.778) (xy -0.9652 1.778) (xy -0.9652 -1.778)
			)
			(stroke
				(width 0)
				(type default)
			)
			(fill no)
			(layer "F.CrtYd")
		)
		(fp_rect
			(start -0.9652 1.778)
			(end 0.9652 -1.778)
			(stroke
				(width 0)
				(type default)
			)
			(fill no)
			(layer "F.Fab")
		)
		(pad "1" smd rect
			(at 0 -0.9652 90)
			(size 1.397 1.143)
			(layers "F.Cu" "F.Mask" "F.Paste")
			(net "MB3_12V_CTRL_GATE2")
		)
		(pad "2" smd rect
			(at 0 0.9652 90)
			(size 1.397 1.143)
			(layers "F.Cu" "F.Mask" "F.Paste")
			(net "MB3_CM_GATE_R")
		)
	)
	(footprint ""
		(layer "F.Cu")
		(at 426.085 -44.958 180)
		(property "Reference" "C464"
			(at 0 0 180)
			(layer "F.SilkS")
			(hide yes)
			(effects
				(font
					(size 1.27 1.27)
				)
			)
		)
		(property "Value" "SC4D7U25V5KX-1-GP"
			(at -0.0762 -6.1214 180)
			(unlocked yes)
			(layer "F.Fab")
			(hide yes)
			(effects
				(font
					(size 1.016 1.016)
					(thickness 0.1524)
				)
			)
		)
		(property "Device Type" "C805H58"
			(at -0.0762 -8.1534 180)
			(unlocked yes)
			(layer "F.Fab")
			(hide yes)
			(effects
				(font
					(size 1.016 1.016)
					(thickness 0.1524)
				)
			)
		)
		(duplicate_pad_numbers_are_jumpers no)
		(fp_line
			(start 0.635 0)
			(end -0.635 0)
			(stroke
				(width 0.508)
				(type default)
			)
			(layer "F.SilkS")
		)
		(fp_rect
			(start -0.9652 1.778)
			(end 0.9652 -1.778)
			(stroke
				(width 0)
				(type default)
			)
			(fill no)
			(layer "F.CrtYd")
		)
		(fp_poly
			(pts
				(xy -0.9652 -1.778) (xy 0.9652 -1.778) (xy 0.9652 1.778) (xy -0.9652 1.778)
			)
			(stroke
				(width 0)
				(type default)
			)
			(fill no)
			(layer "F.Fab")
		)
		(pad "1" smd rect
			(at 0 -0.9652 180)
			(size 1.397 1.143)
			(layers "F.Cu" "F.Mask" "F.Paste")
			(net "P12V_HDD33")
		)
		(pad "2" smd rect
			(at 0 0.9652 180)
			(size 1.397 1.143)
			(layers "F.Cu" "F.Mask" "F.Paste")
			(net "GND")
		)
	)
	(footprint ""
		(layer "F.Cu")
		(at 457.935838 -228.930454 -90)
		(property "Reference" "R1145"
			(at 0 0 270)
			(layer "F.SilkS")
			(hide yes)
			(effects
				(font
					(size 1.27 1.27)
				)
			)
		)
		(property "Value" "200KR2F-L-GP"
			(at 0.064008 -3.993896 270)
			(unlocked yes)
			(layer "F.Fab")
			(hide yes)
			(effects
				(font
					(size 1.016 1.016)
					(thickness 0.1524)
				)
			)
		)
		(property "Device Type" "R402H16"
			(at 0.064008 -5.517896 270)
			(unlocked yes)
			(layer "F.Fab")
			(hide yes)
			(effects
				(font
					(size 1.016 1.016)
					(thickness 0.1524)
				)
			)
		)
		(duplicate_pad_numbers_are_jumpers no)
		(fp_line
			(start -0.508 -0.9398)
			(end -0.508 0.9398)
			(stroke
				(width 0.1524)
				(type default)
			)
			(layer "F.SilkS")
		)
		(fp_line
			(start 0.508 -0.9398)
			(end -0.508 -0.9398)
			(stroke
				(width 0.1524)
				(type default)
			)
			(layer "F.SilkS")
		)
		(fp_rect
			(start -0.508 0.9398)
			(end 0.508 -0.9398)
			(stroke
				(width 0)
				(type default)
			)
			(fill no)
			(layer "F.CrtYd")
		)
		(fp_rect
			(start -0.508 0.9398)
			(end 0.508 -0.9398)
			(stroke
				(width 0)
				(type default)
			)
			(fill no)
			(layer "F.Fab")
		)
		(pad "1" smd custom
			(at 0 -0.4445 270)
			(size 0.1397 0.1397)
			(layers "F.Cu" "F.Mask" "F.Paste")
			(net "P5V_B_3_MODE")
			(options
				(clearance outline)
				(anchor circle)
			)
			(primitives
				(gr_poly
					(pts
						(arc
							(start -0.1778 -0.2794)
							(mid -0.249642 -0.249642)
							(end -0.2794 -0.1778)
						)
						(arc
							(start -0.2794 0.1778)
							(mid -0.249642 0.249642)
							(end -0.1778 0.2794)
						)
						(arc
							(start 0.1778 0.2794)
							(mid 0.249642 0.249642)
							(end 0.2794 0.1778)
						)
						(arc
							(start 0.2794 -0.1778)
							(mid 0.249642 -0.249642)
							(end 0.1778 -0.2794)
						)
					)
					(width 0)
					(fill yes)
				)
			)
		)
		(pad "2" smd custom
			(at 0 0.4445 270)
			(size 0.1397 0.1397)
			(layers "F.Cu" "F.Mask" "F.Paste")
			(net "P5V_B_3_PGOOD")
			(options
				(clearance outline)
				(anchor circle)
			)
			(primitives
				(gr_poly
					(pts
						(arc
							(start -0.1778 -0.2794)
							(mid -0.249642 -0.249642)
							(end -0.2794 -0.1778)
						)
						(arc
							(start -0.2794 0.1778)
							(mid -0.249642 0.249642)
							(end -0.1778 0.2794)
						)
						(arc
							(start 0.1778 0.2794)
							(mid 0.249642 0.249642)
							(end 0.2794 0.1778)
						)
						(arc
							(start 0.2794 -0.1778)
							(mid 0.249642 -0.249642)
							(end 0.1778 -0.2794)
						)
					)
					(width 0)
					(fill yes)
				)
			)
		)
	)
	(footprint ""
		(layer "F.Cu")
		(at 431.451004 -362.077 180)
		(property "Reference" "Q214"
			(at 0 0 180)
			(layer "F.SilkS")
			(hide yes)
			(effects
				(font
					(size 1.27 1.27)
				)
			)
		)
		(property "Value" "2N7002K-2-GP"
			(at 0.127 -8.9662 180)
			(unlocked yes)
			(layer "F.Fab")
			(hide yes)
			(effects
				(font
					(size 1.016 1.016)
					(thickness 0.1524)
				)
			)
		)
		(property "Device Type" "SOT23DGS2D4H44"
			(at 0.127 -10.4902 180)
			(unlocked yes)
			(layer "F.Fab")
			(hide yes)
			(effects
				(font
					(size 1.016 1.016)
					(thickness 0.1524)
				)
			)
		)
		(duplicate_pad_numbers_are_jumpers no)
		(fp_line
			(start 1.651 1.778)
			(end 1.651 -1.778)
			(stroke
				(width 0.1524)
				(type default)
			)
			(layer "F.SilkS")
		)
		(fp_line
			(start 1.651 -1.778)
			(end -1.651 -1.778)
			(stroke
				(width 0.1524)
				(type default)
			)
			(layer "F.SilkS")
		)
		(fp_line
			(start -1.651 1.778)
			(end 1.651 1.778)
			(stroke
				(width 0.1524)
				(type default)
			)
			(layer "F.SilkS")
		)
		(fp_line
			(start -1.651 -1.778)
			(end -1.651 1.778)
			(stroke
				(width 0.1524)
				(type default)
			)
			(layer "F.SilkS")
		)
		(fp_poly
			(pts
				(xy -1.778 1.8796) (xy -1.778 -1.8796) (xy 1.778 -1.8796) (xy 1.778 1.8796)
			)
			(stroke
				(width 0)
				(type default)
			)
			(fill no)
			(layer "F.CrtYd")
		)
		(fp_poly
			(pts
				(xy -1.778 1.8796) (xy -1.778 -1.8796) (xy 1.778 -1.8796) (xy 1.778 1.8796)
			)
			(stroke
				(width 0)
				(type default)
			)
			(fill no)
			(layer "F.Fab")
		)
		(pad "D" smd custom
			(at 0 -0.9525 180)
			(size 0.1905 0.1905)
			(layers "F.Cu" "F.Mask" "F.Paste")
			(net "GATE_FAN3")
			(options
				(clearance outline)
				(anchor circle)
			)
			(primitives
				(gr_poly
					(pts
						(arc
							(start -0.1778 0.5715)
							(mid -0.321484 0.511984)
							(end -0.381 0.3683)
						)
						(arc
							(start -0.381 -0.3683)
							(mid -0.321484 -0.511984)
							(end -0.1778 -0.5715)
						)
						(arc
							(start 0.1778 -0.5715)
							(mid 0.321484 -0.511984)
							(end 0.381 -0.3683)
						)
						(arc
							(start 0.381 0.3683)
							(mid 0.321484 0.511984)
							(end 0.1778 0.5715)
						)
					)
					(width 0)
					(fill yes)
				)
			)
		)
		(pad "G" smd custom
			(at -0.98425 0.9525 180)
			(size 0.1905 0.1905)
			(layers "F.Cu" "F.Mask" "F.Paste")
			(net "FAN_EN")
			(options
				(clearance outline)
				(anchor circle)
			)
			(primitives
				(gr_poly
					(pts
						(arc
							(start -0.1778 0.5715)
							(mid -0.321484 0.511984)
							(end -0.381 0.3683)
						)
						(arc
							(start -0.381 -0.3683)
							(mid -0.321484 -0.511984)
							(end -0.1778 -0.5715)
						)
						(arc
							(start 0.1778 -0.5715)
							(mid 0.321484 -0.511984)
							(end 0.381 -0.3683)
						)
						(arc
							(start 0.381 0.3683)
							(mid 0.321484 0.511984)
							(end 0.1778 0.5715)
						)
					)
					(width 0)
					(fill yes)
				)
			)
		)
		(pad "S" smd custom
			(at 0.98425 0.9525 180)
			(size 0.1905 0.1905)
			(layers "F.Cu" "F.Mask" "F.Paste")
			(net "GND")
			(options
				(clearance outline)
				(anchor circle)
			)
			(primitives
				(gr_poly
					(pts
						(arc
							(start -0.1778 0.5715)
							(mid -0.321484 0.511984)
							(end -0.381 0.3683)
						)
						(arc
							(start -0.381 -0.3683)
							(mid -0.321484 -0.511984)
							(end -0.1778 -0.5715)
						)
						(arc
							(start 0.1778 -0.5715)
							(mid 0.321484 -0.511984)
							(end 0.381 -0.3683)
						)
						(arc
							(start 0.381 0.3683)
							(mid 0.321484 0.511984)
							(end 0.1778 0.5715)
						)
					)
					(width 0)
					(fill yes)
				)
			)
		)
	)
	(footprint ""
		(layer "F.Cu")
		(at 24.450802 -230.63835 -90)
		(property "Reference" "R1100"
			(at 0 0 270)
			(layer "F.SilkS")
			(hide yes)
			(effects
				(font
					(size 1.27 1.27)
				)
			)
		)
		(property "Value" "10KR2F-2-GP"
			(at 0.064008 -3.993896 270)
			(unlocked yes)
			(layer "F.Fab")
			(hide yes)
			(effects
				(font
					(size 1.016 1.016)
					(thickness 0.1524)
				)
			)
		)
		(property "Device Type" "R402H16"
			(at 0.064008 -5.517896 270)
			(unlocked yes)
			(layer "F.Fab")
			(hide yes)
			(effects
				(font
					(size 1.016 1.016)
					(thickness 0.1524)
				)
			)
		)
		(duplicate_pad_numbers_are_jumpers no)
		(fp_line
			(start -0.508 -0.9398)
			(end -0.508 0.9398)
			(stroke
				(width 0.1524)
				(type default)
			)
			(layer "F.SilkS")
		)
		(fp_line
			(start 0.508 -0.9398)
			(end -0.508 -0.9398)
			(stroke
				(width 0.1524)
				(type default)
			)
			(layer "F.SilkS")
		)
		(fp_rect
			(start -0.508 0.9398)
			(end 0.508 -0.9398)
			(stroke
				(width 0)
				(type default)
			)
			(fill no)
			(layer "F.CrtYd")
		)
		(fp_rect
			(start -0.508 0.9398)
			(end 0.508 -0.9398)
			(stroke
				(width 0)
				(type default)
			)
			(fill no)
			(layer "F.Fab")
		)
		(pad "1" smd custom
			(at 0 -0.4445 270)
			(size 0.1397 0.1397)
			(layers "F.Cu" "F.Mask" "F.Paste")
			(net "P5V_B_1_EN_R")
			(options
				(clearance outline)
				(anchor circle)
			)
			(primitives
				(gr_poly
					(pts
						(arc
							(start -0.1778 -0.2794)
							(mid -0.249642 -0.249642)
							(end -0.2794 -0.1778)
						)
						(arc
							(start -0.2794 0.1778)
							(mid -0.249642 0.249642)
							(end -0.1778 0.2794)
						)
						(arc
							(start 0.1778 0.2794)
							(mid 0.249642 0.249642)
							(end 0.2794 0.1778)
						)
						(arc
							(start 0.2794 -0.1778)
							(mid 0.249642 -0.249642)
							(end 0.1778 -0.2794)
						)
					)
					(width 0)
					(fill yes)
				)
			)
		)
		(pad "2" smd custom
			(at 0 0.4445 270)
			(size 0.1397 0.1397)
			(layers "F.Cu" "F.Mask" "F.Paste")
			(net "GND")
			(options
				(clearance outline)
				(anchor circle)
			)
			(primitives
				(gr_poly
					(pts
						(arc
							(start -0.1778 -0.2794)
							(mid -0.249642 -0.249642)
							(end -0.2794 -0.1778)
						)
						(arc
							(start -0.2794 0.1778)
							(mid -0.249642 0.249642)
							(end -0.1778 0.2794)
						)
						(arc
							(start 0.1778 0.2794)
							(mid 0.249642 0.249642)
							(end 0.2794 0.1778)
						)
						(arc
							(start 0.2794 -0.1778)
							(mid 0.249642 -0.249642)
							(end 0.1778 -0.2794)
						)
					)
					(width 0)
					(fill yes)
				)
			)
		)
	)
)
